(kicad_pcb
	(version 20221018)
	(generator pcbnew)
	(general
    (thickness 1.7403)
  )
	(paper "A4")
	(title_block
    (title "Data Center RDIMM DDR4 Tester")
    (date "2024-09-30")
    (rev "1.2.4")
		(comment 9 "footprints 143-153 of 690")
	)
	(layers
    (0 "F.Cu" signal)
    (1 "In1.Cu" power)
    (2 "In2.Cu" signal)
    (3 "In3.Cu" power)
    (4 "In4.Cu" power)
    (5 "In5.Cu" signal)
    (6 "In6.Cu" power)
    (7 "In7.Cu" signal)
    (8 "In8.Cu" power)
    (9 "In9.Cu" signal)
    (10 "In10.Cu" power)
    (31 "B.Cu" signal)
    (32 "B.Adhes" user "B.Adhesive")
    (33 "F.Adhes" user "F.Adhesive")
    (34 "B.Paste" user)
    (35 "F.Paste" user)
    (36 "B.SilkS" user "B.Silkscreen")
    (37 "F.SilkS" user "F.Silkscreen")
    (38 "B.Mask" user)
    (39 "F.Mask" user)
    (40 "Dwgs.User" user "User.Drawings")
    (41 "Cmts.User" user "User.Comments")
    (42 "Eco1.User" user "User.Eco1")
    (43 "Eco2.User" user "User.Eco2")
    (44 "Edge.Cuts" user)
    (45 "Margin" user)
    (46 "B.CrtYd" user "B.Courtyard")
    (47 "F.CrtYd" user "F.Courtyard")
    (48 "B.Fab" user)
    (49 "F.Fab" user)
  )
	(footprint "data-center-rdimm-ddr4-tester-footprints:R_0402_1005Metric" (layer "F.Cu")
    (at 222.225 87.85)
    (descr "Resistor SMD 0402")
    (tags "resistor SMD 0402")
    (property "Author" "Antmicro")
    (property "Current" "1A")
    (property "License" "Apache-2.0")
    (property "MPN" "ERJ2GE0R00X")
    (property "Manufacturer" "Panasonic")
    (property "Sheetfile" "config-spi.kicad_sch")
    (property "Sheetname" "Config SPI flash")
    (property "Tolerance" "")
    (property "Val" "0R")
    (property "ki_description" "0R resistor in 0402 package with unspecified tolerance")
    (attr smd)
    (fp_text reference "R13" (at -1.135 2.51) (layer "F.SilkS")
        (effects (font (size 0.7 0.7) (thickness 0.15)) (justify left bottom))
    )
    (fp_text value "R_0R_0402" (at 0 1.4) (layer "F.Fab") hide
        (effects (font (size 0.7 0.7) (thickness 0.15)) (justify left bottom))
    )
    (fp_text user "License: Apache-2.0" (at -0.95 5.169) (layer "F.Fab") hide
        (effects (font (size 0.7 0.7) (thickness 0.15)) (justify left bottom))
    )
    (fp_text user "${REFERENCE}" (at -0.95 3.168) (layer "F.Fab") hide
        (effects (font (size 0.7 0.7) (thickness 0.15)) (justify left bottom))
    )
    (fp_text user "Author: Antmicro" (at -0.95 4.169) (layer "F.Fab") hide
        (effects (font (size 0.7 0.7) (thickness 0.15)) (justify left bottom))
    )
    (fp_rect (start -0.93 -0.47) (end 0.93 0.47)
      (stroke (width 0.05) (type solid)) (fill none) (layer "F.CrtYd"))
    (fp_rect (start -0.5 -0.25) (end 0.5 0.25)
      (stroke (width 0.15) (type solid)) (fill none) (layer "F.Fab"))
    (pad "1" smd roundrect (at -0.485 0) (size 0.59 0.64) (layers "F.Cu" "F.Paste" "F.Mask") (roundrect_rratio 0.25)
      (net 24 "MODE1") (pintype "passive"))
    (pad "2" smd roundrect (at 0.485 0) (size 0.59 0.64) (layers "F.Cu" "F.Paste" "F.Mask") (roundrect_rratio 0.25)
      (net 9 "GND") (pintype "passive"))
  )
	(footprint "data-center-rdimm-ddr4-tester-footprints:R_0402_1005Metric" (layer "F.Cu")
    (at 224.295 87.85)
    (descr "Resistor SMD 0402")
    (tags "resistor SMD 0402")
    (property "Author" "Antmicro")
    (property "License" "Apache-2.0")
    (property "MPN" "CR0402-FX-4701GLF")
    (property "Manufacturer" "Bourns")
    (property "Sheetfile" "config-spi.kicad_sch")
    (property "Sheetname" "Config SPI flash")
    (property "Tolerance" "1%")
    (property "Val" "4k7")
    (property "ki_description" "4k7 resistor in 0402 package with 1% tolerance")
    (attr smd)
    (fp_text reference "R32" (at -1.095 2.51) (layer "F.SilkS")
        (effects (font (size 0.7 0.7) (thickness 0.15)) (justify left bottom))
    )
    (fp_text value "R_4k7_0402" (at 0 1.4) (layer "F.Fab") hide
        (effects (font (size 0.7 0.7) (thickness 0.15)) (justify left bottom))
    )
    (fp_text user "${REFERENCE}" (at -0.95 3.168) (layer "F.Fab") hide
        (effects (font (size 0.7 0.7) (thickness 0.15)) (justify left bottom))
    )
    (fp_text user "License: Apache-2.0" (at -0.95 5.169) (layer "F.Fab") hide
        (effects (font (size 0.7 0.7) (thickness 0.15)) (justify left bottom))
    )
    (fp_text user "Author: Antmicro" (at -0.95 4.169) (layer "F.Fab") hide
        (effects (font (size 0.7 0.7) (thickness 0.15)) (justify left bottom))
    )
    (fp_rect (start -0.93 -0.47) (end 0.93 0.47)
      (stroke (width 0.05) (type solid)) (fill none) (layer "F.CrtYd"))
    (fp_rect (start -0.5 -0.25) (end 0.5 0.25)
      (stroke (width 0.15) (type solid)) (fill none) (layer "F.Fab"))
    (pad "1" smd roundrect (at -0.485 0) (size 0.59 0.64) (layers "F.Cu" "F.Paste" "F.Mask") (roundrect_rratio 0.25)
      (net 143 "3V3_SYS") (pintype "passive"))
    (pad "2" smd roundrect (at 0.485 0) (size 0.59 0.64) (layers "F.Cu" "F.Paste" "F.Mask") (roundrect_rratio 0.25)
      (net 91 "PROGRAM_B") (pintype "passive"))
  )
	(footprint "data-center-rdimm-ddr4-tester-footprints:Testpoint_smd_1mm" (layer "F.Cu")
    (at 110 98.1 90)
    (property "Author" "Antmicro")
    (property "License" "Apache-2.0")
    (property "MPN" "")
    (property "Manufacturer" "")
    (property "Sheetfile" "supply.kicad_sch")
    (property "Sheetname" "Supply")
    (property "ki_description" "Test Point 1mm")
    (attr exclude_from_pos_files)
    (fp_text reference "VIN1" (at -0.34 0.65 180) (layer "F.SilkS")
        (effects (font (size 0.7 0.7) (thickness 0.15)) (justify left bottom))
    )
    (fp_text value "TP_1mm_SMD" (at 0 1.4 90) (layer "F.Fab") hide
        (effects (font (size 0.7 0.7) (thickness 0.15)) (justify left bottom))
    )
    (fp_text user "${REFERENCE}" (at -0.5 2.8 90) (layer "F.Fab") hide
        (effects (font (size 0.7 0.7) (thickness 0.15)) (justify left bottom))
    )
    (fp_text user "License: Apache-2.0" (at -0.5 5.2 90) (layer "F.Fab") hide
        (effects (font (size 0.7 0.7) (thickness 0.15)) (justify left bottom))
    )
    (fp_text user "Author: Antmicro" (at -0.5 4 90) (layer "F.Fab") hide
        (effects (font (size 0.7 0.7) (thickness 0.15)) (justify left bottom))
    )
    (pad "1" smd circle (at 0 0 90) (size 1 1) (layers "F.Cu" "F.Mask")
      (net 103 "VIN") (pinfunction "1") (pintype "passive"))
  )
	(footprint "data-center-rdimm-ddr4-tester-footprints:Testpoint_smd_1mm" (layer "F.Cu")
    (at 129.986328 79.560008 90)
    (property "Author" "Antmicro")
    (property "License" "Apache-2.0")
    (property "MPN" "")
    (property "Manufacturer" "")
    (property "Sheetfile" "supply.kicad_sch")
    (property "Sheetname" "Supply")
    (property "ki_description" "Test Point 1mm")
    (attr exclude_from_pos_files)
    (fp_text reference "1V8" (at 0.560008 -1.046328 180) (layer "F.SilkS")
        (effects (font (size 0.7 0.7) (thickness 0.15)) (justify left bottom))
    )
    (fp_text value "TP_1mm_SMD" (at 0 1.4 90) (layer "F.Fab") hide
        (effects (font (size 0.7 0.7) (thickness 0.15)) (justify left bottom))
    )
    (fp_text user "${REFERENCE}" (at -0.5 2.8 90) (layer "F.Fab") hide
        (effects (font (size 0.7 0.7) (thickness 0.15)) (justify left bottom))
    )
    (fp_text user "Author: Antmicro" (at -0.5 4 90) (layer "F.Fab") hide
        (effects (font (size 0.7 0.7) (thickness 0.15)) (justify left bottom))
    )
    (fp_text user "License: Apache-2.0" (at -0.5 5.2 90) (layer "F.Fab") hide
        (effects (font (size 0.7 0.7) (thickness 0.15)) (justify left bottom))
    )
    (pad "1" smd circle (at 0 0 90) (size 1 1) (layers "F.Cu" "F.Mask")
      (net 302 "VCC1V8") (pinfunction "1") (pintype "passive"))
  )
	(footprint "data-center-rdimm-ddr4-tester-footprints:Testpoint_smd_1mm" (layer "F.Cu")
    (at 132.786328 109.710008 180)
    (property "Author" "Antmicro")
    (property "License" "Apache-2.0")
    (property "MPN" "")
    (property "Manufacturer" "")
    (property "Sheetfile" "supply.kicad_sch")
    (property "Sheetname" "Supply")
    (property "ki_description" "Test Point 1mm")
    (attr exclude_from_pos_files)
    (fp_text reference "5V0" (at -0.653672 -0.359992 180) (layer "F.SilkS")
        (effects (font (size 0.7 0.7) (thickness 0.15)) (justify left bottom))
    )
    (fp_text value "TP_1mm_SMD" (at 0 1.4 180) (layer "F.Fab") hide
        (effects (font (size 0.7 0.7) (thickness 0.15)) (justify left bottom))
    )
    (fp_text user "License: Apache-2.0" (at -0.5 5.2 180) (layer "F.Fab") hide
        (effects (font (size 0.7 0.7) (thickness 0.15)) (justify left bottom))
    )
    (fp_text user "${REFERENCE}" (at -0.5 2.8 180) (layer "F.Fab") hide
        (effects (font (size 0.7 0.7) (thickness 0.15)) (justify left bottom))
    )
    (fp_text user "Author: Antmicro" (at -0.5 4 180) (layer "F.Fab") hide
        (effects (font (size 0.7 0.7) (thickness 0.15)) (justify left bottom))
    )
    (pad "1" smd circle (at 0 0 180) (size 1 1) (layers "F.Cu" "F.Mask")
      (net 104 "VCC5V0") (pinfunction "1") (pintype "passive"))
  )
	(footprint "data-center-rdimm-ddr4-tester-footprints:C_0603_1608Metric" (layer "F.Cu")
    (at 115.786328 80.560008 180)
    (descr "Capacitor SMD 0603")
    (tags "capacitor 0603")
    (property "Author" "Antmicro")
    (property "Dielectric" "")
    (property "License" "Apache-2.0")
    (property "MPN" "06031C103JAT2A")
    (property "Manufacturer" "AVX")
    (property "Sheetfile" "supply.kicad_sch")
    (property "Sheetname" "Supply")
    (property "Val" "10n")
    (property "Voltage" "")
    (property "ki_description" " ")
    (attr smd)
    (fp_text reference "C106" (at 1.446328 9.710008 180) (layer "F.SilkS")
        (effects (font (size 0.7 0.7) (thickness 0.15)) (justify left bottom))
    )
    (fp_text value "C_10n_0603" (at 0 1.6 180) (layer "F.Fab") hide
        (effects (font (size 0.7 0.7) (thickness 0.15)) (justify left bottom))
    )
    (fp_text user "Author: Antmicro" (at -1.682 4.894 180) (layer "F.Fab") hide
        (effects (font (size 0.7 0.7) (thickness 0.15)) (justify left bottom))
    )
    (fp_text user "${REFERENCE}" (at -1.682 3.895 180) (layer "F.Fab") hide
        (effects (font (size 0.7 0.7) (thickness 0.15)) (justify left bottom))
    )
    (fp_text user "License: Apache-2.0" (at -1.682 5.895 180) (layer "F.Fab") hide
        (effects (font (size 0.7 0.7) (thickness 0.15)) (justify left bottom))
    )
    (fp_line (start -0.3 -0.3) (end 0.3 -0.3)
      (stroke (width 0.15) (type solid)) (layer "F.SilkS"))
    (fp_line (start -0.3 0.3) (end 0.3 0.3)
      (stroke (width 0.15) (type solid)) (layer "F.SilkS"))
    (fp_rect (start -1.24 -0.7) (end 1.24 0.7)
      (stroke (width 0.05) (type solid)) (fill none) (layer "F.CrtYd"))
    (fp_rect (start -0.8 -0.4) (end 0.8 0.4)
      (stroke (width 0.15) (type solid)) (fill none) (layer "F.Fab"))
    (pad "1" smd roundrect (at -0.7 0 180) (size 0.6 0.8) (layers "F.Cu" "F.Paste" "F.Mask") (roundrect_rratio 0.2)
      (net 77 "VDDQ") (pintype "passive"))
    (pad "2" smd roundrect (at 0.7 0 180) (size 0.6 0.8) (layers "F.Cu" "F.Paste" "F.Mask") (roundrect_rratio 0.2)
      (net 9 "GND") (pintype "passive"))
  )
	(footprint "data-center-rdimm-ddr4-tester-footprints:C_0603_1608Metric" (layer "F.Cu")
    (at 115.786328 79.060008 180)
    (descr "Capacitor SMD 0603")
    (tags "capacitor 0603")
    (property "Author" "Antmicro")
    (property "Dielectric" "")
    (property "License" "Apache-2.0")
    (property "MPN" "06031C103JAT2A")
    (property "Manufacturer" "AVX")
    (property "Sheetfile" "supply.kicad_sch")
    (property "Sheetname" "Supply")
    (property "Val" "10n")
    (property "Voltage" "")
    (property "ki_description" " ")
    (attr smd)
    (fp_text reference "C108" (at 1.436328 9.150008 180) (layer "F.SilkS")
        (effects (font (size 0.7 0.7) (thickness 0.15)) (justify left bottom))
    )
    (fp_text value "C_10n_0603" (at 0 1.6 180) (layer "F.Fab") hide
        (effects (font (size 0.7 0.7) (thickness 0.15)) (justify left bottom))
    )
    (fp_text user "Author: Antmicro" (at -1.682 4.894 180) (layer "F.Fab") hide
        (effects (font (size 0.7 0.7) (thickness 0.15)) (justify left bottom))
    )
    (fp_text user "License: Apache-2.0" (at -1.682 5.895 180) (layer "F.Fab") hide
        (effects (font (size 0.7 0.7) (thickness 0.15)) (justify left bottom))
    )
    (fp_text user "${REFERENCE}" (at -1.682 3.895 180) (layer "F.Fab") hide
        (effects (font (size 0.7 0.7) (thickness 0.15)) (justify left bottom))
    )
    (fp_line (start -0.3 -0.3) (end 0.3 -0.3)
      (stroke (width 0.15) (type solid)) (layer "F.SilkS"))
    (fp_line (start -0.3 0.3) (end 0.3 0.3)
      (stroke (width 0.15) (type solid)) (layer "F.SilkS"))
    (fp_rect (start -1.24 -0.7) (end 1.24 0.7)
      (stroke (width 0.05) (type solid)) (fill none) (layer "F.CrtYd"))
    (fp_rect (start -0.8 -0.4) (end 0.8 0.4)
      (stroke (width 0.15) (type solid)) (fill none) (layer "F.Fab"))
    (pad "1" smd roundrect (at -0.7 0 180) (size 0.6 0.8) (layers "F.Cu" "F.Paste" "F.Mask") (roundrect_rratio 0.2)
      (net 77 "VDDQ") (pintype "passive"))
    (pad "2" smd roundrect (at 0.7 0 180) (size 0.6 0.8) (layers "F.Cu" "F.Paste" "F.Mask") (roundrect_rratio 0.2)
      (net 9 "GND") (pintype "passive"))
  )
	(footprint "data-center-rdimm-ddr4-tester-footprints:C_0603_1608Metric" (layer "F.Cu")
    (at 125.686328 82.860008)
    (descr "Capacitor SMD 0603")
    (tags "capacitor 0603")
    (property "Author" "Antmicro")
    (property "Dielectric" "")
    (property "License" "Apache-2.0")
    (property "MPN" "06031C103JAT2A")
    (property "Manufacturer" "AVX")
    (property "Sheetfile" "supply.kicad_sch")
    (property "Sheetname" "Supply")
    (property "Val" "10n")
    (property "Voltage" "")
    (property "ki_description" " ")
    (attr smd)
    (fp_text reference "C110" (at -1.406328 -3.230008) (layer "F.SilkS")
        (effects (font (size 0.7 0.7) (thickness 0.15)) (justify left bottom))
    )
    (fp_text value "C_10n_0603" (at 0 1.6) (layer "F.Fab") hide
        (effects (font (size 0.7 0.7) (thickness 0.15)) (justify left bottom))
    )
    (fp_text user "${REFERENCE}" (at -1.682 3.895) (layer "F.Fab") hide
        (effects (font (size 0.7 0.7) (thickness 0.15)) (justify left bottom))
    )
    (fp_text user "Author: Antmicro" (at -1.682 4.894) (layer "F.Fab") hide
        (effects (font (size 0.7 0.7) (thickness 0.15)) (justify left bottom))
    )
    (fp_text user "License: Apache-2.0" (at -1.682 5.895) (layer "F.Fab") hide
        (effects (font (size 0.7 0.7) (thickness 0.15)) (justify left bottom))
    )
    (fp_line (start -0.3 -0.3) (end 0.3 -0.3)
      (stroke (width 0.15) (type solid)) (layer "F.SilkS"))
    (fp_line (start -0.3 0.3) (end 0.3 0.3)
      (stroke (width 0.15) (type solid)) (layer "F.SilkS"))
    (fp_rect (start -1.24 -0.7) (end 1.24 0.7)
      (stroke (width 0.05) (type solid)) (fill none) (layer "F.CrtYd"))
    (fp_rect (start -0.8 -0.4) (end 0.8 0.4)
      (stroke (width 0.15) (type solid)) (fill none) (layer "F.Fab"))
    (pad "1" smd roundrect (at -0.7 0) (size 0.6 0.8) (layers "F.Cu" "F.Paste" "F.Mask") (roundrect_rratio 0.2)
      (net 184 "VPP") (pintype "passive"))
    (pad "2" smd roundrect (at 0.7 0) (size 0.6 0.8) (layers "F.Cu" "F.Paste" "F.Mask") (roundrect_rratio 0.2)
      (net 9 "GND") (pintype "passive"))
  )
	(footprint "data-center-rdimm-ddr4-tester-footprints:C_0603_1608Metric" (layer "F.Cu")
    (at 125.686328 87.310008)
    (descr "Capacitor SMD 0603")
    (tags "capacitor 0603")
    (property "Author" "Antmicro")
    (property "Dielectric" "")
    (property "License" "Apache-2.0")
    (property "MPN" "06031C103JAT2A")
    (property "Manufacturer" "AVX")
    (property "Sheetfile" "supply.kicad_sch")
    (property "Sheetname" "Supply")
    (property "Val" "10n")
    (property "Voltage" "")
    (property "ki_description" " ")
    (attr smd)
    (fp_text reference "C111" (at -1.386328 -5.000008) (layer "F.SilkS")
        (effects (font (size 0.7 0.7) (thickness 0.15)) (justify left bottom))
    )
    (fp_text value "C_10n_0603" (at 0 1.6) (layer "F.Fab") hide
        (effects (font (size 0.7 0.7) (thickness 0.15)) (justify left bottom))
    )
    (fp_text user "Author: Antmicro" (at -1.682 4.894) (layer "F.Fab") hide
        (effects (font (size 0.7 0.7) (thickness 0.15)) (justify left bottom))
    )
    (fp_text user "${REFERENCE}" (at -1.682 3.895) (layer "F.Fab") hide
        (effects (font (size 0.7 0.7) (thickness 0.15)) (justify left bottom))
    )
    (fp_text user "License: Apache-2.0" (at -1.682 5.895) (layer "F.Fab") hide
        (effects (font (size 0.7 0.7) (thickness 0.15)) (justify left bottom))
    )
    (fp_line (start -0.3 -0.3) (end 0.3 -0.3)
      (stroke (width 0.15) (type solid)) (layer "F.SilkS"))
    (fp_line (start -0.3 0.3) (end 0.3 0.3)
      (stroke (width 0.15) (type solid)) (layer "F.SilkS"))
    (fp_rect (start -1.24 -0.7) (end 1.24 0.7)
      (stroke (width 0.05) (type solid)) (fill none) (layer "F.CrtYd"))
    (fp_rect (start -0.8 -0.4) (end 0.8 0.4)
      (stroke (width 0.15) (type solid)) (fill none) (layer "F.Fab"))
    (pad "1" smd roundrect (at -0.7 0) (size 0.6 0.8) (layers "F.Cu" "F.Paste" "F.Mask") (roundrect_rratio 0.2)
      (net 184 "VPP") (pintype "passive"))
    (pad "2" smd roundrect (at 0.7 0) (size 0.6 0.8) (layers "F.Cu" "F.Paste" "F.Mask") (roundrect_rratio 0.2)
      (net 9 "GND") (pintype "passive"))
  )
	(footprint "data-center-rdimm-ddr4-tester-footprints:C_0603_1608Metric" (layer "F.Cu")
    (at 125.686328 84.343341)
    (descr "Capacitor SMD 0603")
    (tags "capacitor 0603")
    (property "Author" "Antmicro")
    (property "Dielectric" "")
    (property "License" "Apache-2.0")
    (property "MPN" "06031C103JAT2A")
    (property "Manufacturer" "AVX")
    (property "Sheetfile" "supply.kicad_sch")
    (property "Sheetname" "Supply")
    (property "Val" "10n")
    (property "Voltage" "")
    (property "ki_description" " ")
    (attr smd)
    (fp_text reference "C112" (at -1.396328 -3.833341) (layer "F.SilkS")
        (effects (font (size 0.7 0.7) (thickness 0.15)) (justify left bottom))
    )
    (fp_text value "C_10n_0603" (at 0 1.6) (layer "F.Fab") hide
        (effects (font (size 0.7 0.7) (thickness 0.15)) (justify left bottom))
    )
    (fp_text user "License: Apache-2.0" (at -1.682 5.895) (layer "F.Fab") hide
        (effects (font (size 0.7 0.7) (thickness 0.15)) (justify left bottom))
    )
    (fp_text user "${REFERENCE}" (at -1.682 3.895) (layer "F.Fab") hide
        (effects (font (size 0.7 0.7) (thickness 0.15)) (justify left bottom))
    )
    (fp_text user "Author: Antmicro" (at -1.682 4.894) (layer "F.Fab") hide
        (effects (font (size 0.7 0.7) (thickness 0.15)) (justify left bottom))
    )
    (fp_line (start -0.3 -0.3) (end 0.3 -0.3)
      (stroke (width 0.15) (type solid)) (layer "F.SilkS"))
    (fp_line (start -0.3 0.3) (end 0.3 0.3)
      (stroke (width 0.15) (type solid)) (layer "F.SilkS"))
    (fp_rect (start -1.24 -0.7) (end 1.24 0.7)
      (stroke (width 0.05) (type solid)) (fill none) (layer "F.CrtYd"))
    (fp_rect (start -0.8 -0.4) (end 0.8 0.4)
      (stroke (width 0.15) (type solid)) (fill none) (layer "F.Fab"))
    (pad "1" smd roundrect (at -0.7 0) (size 0.6 0.8) (layers "F.Cu" "F.Paste" "F.Mask") (roundrect_rratio 0.2)
      (net 184 "VPP") (pintype "passive"))
    (pad "2" smd roundrect (at 0.7 0) (size 0.6 0.8) (layers "F.Cu" "F.Paste" "F.Mask") (roundrect_rratio 0.2)
      (net 9 "GND") (pintype "passive"))
  )
	(footprint "data-center-rdimm-ddr4-tester-footprints:C_0603_1608Metric" (layer "F.Cu")
    (at 115.936328 84.660008 180)
    (descr "Capacitor SMD 0603")
    (tags "capacitor 0603")
    (property "Author" "Antmicro")
    (property "Dielectric" "")
    (property "License" "Apache-2.0")
    (property "MPN" "GRM188R60J226MEA0D")
    (property "Manufacturer" "Murata")
    (property "Sheetfile" "supply.kicad_sch")
    (property "Sheetname" "Supply")
    (property "Val" "22u")
    (property "Voltage" "")
    (property "ki_description" " ")
    (attr smd)
    (fp_text reference "C159" (at 1.576328 11.840008 180) (layer "F.SilkS")
        (effects (font (size 0.7 0.7) (thickness 0.15)) (justify left bottom))
    )
    (fp_text value "C_22u_0603" (at 0 1.6 180) (layer "F.Fab") hide
        (effects (font (size 0.7 0.7) (thickness 0.15)) (justify left bottom))
    )
    (fp_text user "License: Apache-2.0" (at -1.682 5.895 180) (layer "F.Fab") hide
        (effects (font (size 0.7 0.7) (thickness 0.15)) (justify left bottom))
    )
    (fp_text user "Author: Antmicro" (at -1.682 4.894 180) (layer "F.Fab") hide
        (effects (font (size 0.7 0.7) (thickness 0.15)) (justify left bottom))
    )
    (fp_text user "${REFERENCE}" (at -1.682 3.895 180) (layer "F.Fab") hide
        (effects (font (size 0.7 0.7) (thickness 0.15)) (justify left bottom))
    )
    (fp_line (start -0.3 -0.3) (end 0.3 -0.3)
      (stroke (width 0.15) (type solid)) (layer "F.SilkS"))
    (fp_line (start -0.3 0.3) (end 0.3 0.3)
      (stroke (width 0.15) (type solid)) (layer "F.SilkS"))
    (fp_rect (start -1.24 -0.7) (end 1.24 0.7)
      (stroke (width 0.05) (type solid)) (fill none) (layer "F.CrtYd"))
    (fp_rect (start -0.8 -0.4) (end 0.8 0.4)
      (stroke (width 0.15) (type solid)) (fill none) (layer "F.Fab"))
    (pad "1" smd roundrect (at -0.7 0 180) (size 0.6 0.8) (layers "F.Cu" "F.Paste" "F.Mask") (roundrect_rratio 0.2)
      (net 301 "VDD1V2") (pintype "passive"))
    (pad "2" smd roundrect (at 0.7 0 180) (size 0.6 0.8) (layers "F.Cu" "F.Paste" "F.Mask") (roundrect_rratio 0.2)
      (net 9 "GND") (pintype "passive"))
  )
)
